#ISCELL
  mstr_misc dns *
  *
#ISCELL
  mstr_symbols cad_note *
  *
#ISCELL
  mstr_symbols design_note *
  *
#ISCELL
  mstr_symbols intel_corp_bpage *
  *
#CELL
  mstr_discrete res *
  page158_i100
#ISCELL
  mstr_standard offpage *
  page158_i124
#ISCELL
  mstr_standard offpage *
  page158_i125
#ISCELL
  mstr_standard offpage *
  page158_i126
#ISCELL
  mstr_standard offpage *
  page158_i127
#ISCELL
  mstr_standard offpage *
  page158_i128
#ISCELL
  mstr_standard offpage *
  page158_i129
#CELL
  mstr_discrete led *
  page158_i130
#CELL
  mstr_discrete res *
  page158_i131
#ISCELL
  mstr_standard offpage *
  page158_i132
#CELL
  mstr_discrete led *
  page158_i134
#ISCELL
  mstr_symbols p3v3_stby *
  page158_i135
#CELL
  mstr_discrete res *
  page158_i136
#ISCELL
  mstr_standard offpage *
  page158_i137
#ISCELL
  mstr_standard offpage *
  page158_i144
#ISCELL
  mstr_standard offpage *
  page158_i147
#CELL
  mstr_discrete res *
  page158_i148
#CELL
  mstr_discrete res *
  page158_i149
#CELL
  mstr_discrete res *
  page158_i150
#CELL
  mstr_discrete res *
  page158_i152
#CELL
  dev_discrete cap_a *
  page158_i70
#ISCELL
  mstr_symbols gnd *
  page158_i72
#CELL
  mstr_analog fsa3357 *
  page158_i74
#CELL
  mstr_analog fsa3357 *
  page158_i75
#ISCELL
  mstr_symbols gnd *
  page158_i76
#ISCELL
  mstr_symbols gnd *
  page158_i77
#ISCELL
  mstr_symbols p3v3_stby *
  page158_i78
#ISCELL
  mstr_symbols p3v3_stby *
  page158_i79
#ISCELL
  mstr_standard offpage *
  page158_i85
#CELL
  mstr_discrete res *
  page158_i86
#ISCELL
  mstr_standard offpage *
  page158_i87
#CELL
  mstr_discrete res *
  page158_i91
#ISCELL
  mstr_standard offpage *
  page158_i92
#ISCELL
  mstr_standard offpage *
  page158_i93
#ISCELL
  mstr_standard offpage *
  page158_i94
#ISCELL
  mstr_standard offpage *
  page158_i95
#CELL
  dev_discrete cap_a *
  page158_i97
#ISCELL
  mstr_symbols gnd *
  page158_i98
#CELL
  mstr_discrete res *
  page158_i99
